# BASEBOARD_FAB2 (Tioga Pass) — schematic netlist excerpt (pin names and nets, part order shuffled) for the footprints in the layout excerpt that follows; sources: Cadence DE-HDL packaged netlist, KiCad conversion of Wiwynn_Tioga_Pass_MB.brd

U8D7  LCMXO2_A  IC  pkg 256BGA  page 190
  VCC(0)  = P3V3_STBY
  NC(0)  = NC
  PT11C  = FM_PCH_PRSNT_N
  PT10A  = FM_P3V3_CPLD_EN
  PT11A  = TP_CPLD1_PT11A
  PT12D_TDI  = JTAG_PLD_TDI
  PT16C_TCK  = JTAG_PLD_TCK
  PT17B_PCLKC0_1  = TP_CPLD1_PT17B_PCLKC0_1
  PT18C_SCL_PCLKT0_0  = SMB_SENSOR_STBY_LVC3_SCL
  PT19B  = FM_PVCCIN_PVCCSA_CPU0_EN_LVC1
  PT21A  = FM_CPU0_OR_CPU1_MCP_PRES
  PT22B  = PU_THERMTRIP_FORCE_N
  PT24C_INITN  = TP_CPLD1_PT24C_INITN
  PT22D  = TP_CPLD1_PT22D
  PT24B  = TP_CPLD1_PT24B
  VCC(1)  = P3V3_STBY
  PL1C  = RST_PCIE_PCH_PERST_N
  GND(0)  = GND
  PT9C  = FM_CTNR_PS_ON
  PT11D  = PWRGD_PVTT_CPU0
  PT9B  = PWRGD_P12V_MAIN
  PT11B  = TP_CPLD1_PT11B
  PT13A  = TP_CPLD1_PT13A
  PT16D_TMS  = JTAG_PLD_TMS
  PT19A  = PU_RST_PERST_BIT1
  PT20D_PROGRAMN  = PU_CPLD1_PT20D_PROGRAMN
  PT22A  = PWRGD_DSW_PWROK
  PT23B  = FM_PCH_PWRBTN_R1_N
  PT22C  = TP_CPLD1_PT22C
  PT24A  = FM_SINT_PRSNT_N
  GND(1)  = GND
  PR1D  = FM_ADR_COMPLETE_DLY
  PL2C  = RST_PCIE_CPU_DEV1_N
  PL1D  = FM_PCH_PLD_DATA
  GND(2)  = GND
  PT9A  = FM_ADR_SMI_GPIO_R_N
  PT10B  = FM_CPU1_THERMTRIP_LATCH_LVT3_N
  PT12C_TDO  = JTAG_PLD_TDO
  PT13B  = FM_BMC_ONCTL_N
  PT17A_PCLKT0_1  = FM_ADR_COMPLETE
  PT18D_SDA_PCLKC0_0  = SMB_SENSOR_STBY_LVC3_SDA
  PT20C_JTAGENB  = FM_JTAG_PLD_EN_DEBUG
  PT21B  = FM_CPU0_CD_PRES
  PT23A  = FM_SLPS4_N
  PT24D_DONE  = TP_CPLD1_PT24D_DONE
  GND(3)  = GND
  PR1C  = FM_DB1200_PWRGD
  PR2C  = PWRGD_PCH_PWROK
  PL1B_L_GPLLC_FB  = TP_CPLD1_PL1B_L_GPLLC_FB
  PL2D  = FM_MEM_EVENT_FUNC
  PL1A_L_GPLLT_FB  = TP_CPLD1_PL1A_L_GPLLT_FB
  GND(4)  = GND
  VCCIO0(3)  = P3V3_STBY
  PT12A  = RST_PCIE_CPU_DEV0_N
  PT13D  = FM_FORCE_ADR_N
  PT17C  = TP_CPLD1_PT17C
  PT18B  = RST_PCIE_MIDPLANE_N
  PT20A  = TP_CPLD1_PT20A
  PT21D  = FM_CPU0_AND_CPU1_MCP_PRES
  VCCIO0(1)  = P3V3_STBY
  GND(5)  = GND
  PR1A  = PWRGD_SYS_PWROK
  PR2D  = PWRGD_P1V8MCP_CPU0
  PR2A  = PWRGD_P1V8MCP_CPU1
  PL3A_PCLKT5_0  = CLK_32K_SUSCLK_PLD
  PL2A_L_GPLLT_IN  = FM_CPU_CATERR_DLY_LVT3_N
  PL2B_L_GPLLC_IN  = TP_CPLD1_PL2B_L_GPLLC_IN
  VCCIO5(0)  = P3V3_STBY
  GND(6)  = GND
  PT13C  = FM_CPU1_FIVR_FAULT_LVT3_N
  PT12B  = PWRGD_P1V15_BMC_STBY
  PT16B  = TP_CPLD1_PT16B
  PT17D  = FM_SLP_SUS_N
  PT20B  = TP_CPLD1_PT20B
  PT19D  = TP_CPLD1_PT19D
  GND(7)  = GND
  VCCIO1(0)  = P3V3_STBY
  PR2B  = FM_CPLD_ADR_TRIGGER_N
  PR1B  = RST_PLTRST_N
  PR3A  = FM_P1V8MCP_CPU0_EN
  PL4B  = FM_CPU0_PROC_ID0
  PL3B_PCLKC5_0  = FM_CPU0_PKGID0
  PL4A  = FM_CPU0_PROC_ID1
  PL3C  = PU_RST_PERST_BIT0
  PL5C  = FM_CPU0_FIVR_FAULT_LVT3_N
  GND(8)  = GND
  PT16A  = FM_PLD_DEBUG_MODE_N
  PT18A  = SGPIO_BMC_DIN_R
  PT19C  = FM_PS_EN
  PT21C  = FM_CPU1_CD_PRES_N
  GND(9)  = GND
  PR4C  = FM_P1V8MCP_CPU1_EN
  PR3C  = PWRGD_CPUPWRGD
  PR4A  = RST_BMC_SYSRST_BTN_OUT_B_R1_N
  PR3B  = FM_CPU0_MCP_CLK_EN_N
  PR4B  = FM_CPU1_MCP_CLK_EN_N
  PL6A  = FM_SLPS3_N
  PL5A  = FM_CPU0_PKGID2
  PL5B  = FM_CPU0_PKGID1
  PL4D  = RST_RSMRST_R_N
  PL4C  = FM_DEBUG_RST_BTN_N
  PL3D  = FM_PWR_BTN_R2_N
  VCC(4)  = P3V3_STBY
  VCCIO0(0)  = P3V3_STBY
  VCCIO0(2)  = P3V3_STBY
  VCC(5)  = P3V3_STBY
  PR5C  = FM_WBG_PRSNT_N
  PR3D  = FM_CPU0_THERMTRIP_LATCH_LVT3_N
  PR4D  = FM_CPU1_FIVR_FAULT_LVT3
  PR5B  = FM_CPU1_THERMTRIP_LVT3_N
  PR5A  = FM_UV_ADR_TRIGGER_N
  PR6A  = FM_FAST_PROCHOT_THROTTLE_IN_N
  PL7B  = RST_PCIE_CPU_DEV3_N
  PL6B  = FM_PVCCMCP_CPU0_EN
  PL7A  = RST_PCIE_CPU_DEV2_N
  PL6C  = FM_MP_PS_FAIL_N
  PL9C  = NC
  PL5D  = PWRGD_P3V3
  VCCIO4(1)  = P3V3_STBY
  GND(10)  = GND
  GND(11)  = GND
  VCCIO1(1)  = P3V3_STBY
  PR9C  = TP_CPLD1_PR9C
  PR5D  = FM_UV_ADR_TRIGGER_EN
  PR6C  = FM_PVDDQ_GHJ_EN
  PR7A_PCLKT1_0  = TP_CPLD1_PR7A_PCLKT1_0
  PR6B  = FM_PVDDQ_KLM_EN
  PR7B_PCLKC1_0  = TP_CPLD1_PR7B_PCLKC1_0
  PL7C_PCLKT4_0  = SGPIO_BMC_CLK
  PL9A  = SGPIO_BMC_DOUT
  PL7D_PCLKC4_0  = TP_CPLD1_PL7D_PCLKT4_0
  PL9D  = NC
  PL10C  = UART_BMC_RXD5
  PL6D  = PWRGD_P5V
  VCCIO4(0)  = P3V3_STBY
  GND(12)  = GND
  GND(13)  = GND
  VCCIO1(2)  = P3V3_STBY
  PR10C  = TP_CPLD1_PR10C
  PR6D  = FM_FAST_PROCHOT_THROTTLE_DLY_N
  PR9D  = TP_CPLD1_PR9D
  PR7D  = TP_CPLD1_PR7D
  PR9A  = TP_CPLD1_PR9A
  PR7C  = TP_CPLD1_PR7C
  PL9B  = FM_PVCCIOMCP_CPU0_EN
  PL10B  = SP1_BMC_HOST_UART_TX
  PL10A  = SP1_BMC_HOST_UART_RX
  PL11C  = SGPIO_BMC_LD_N
  PL12C  = PWRGD_PVCCIN_CPU0
  PL10D  = UART_BMC_TXD5
  VCC(6)  = P3V3_STBY
  VCCIO2(2)  = P3V3_STBY
  VCCIO2(0)  = P3V3_STBY
  VCC(7)  = P3V3_STBY
  PR12C  = RST_PLTRST_BUF_N
  PR11D  = FM_MEM_THERM_EVENT_PCH_N
  PR11C  = FM_MEM_THERM_EVENT_LVT3_N
  PR10A  = FM_PVDDQ_ABC_EN
  PR10B  = FM_PVDDQ_DEF_EN
  PR9B  = PU_FAB2_MARKER_CPLD
  PL11A  = PWRGD_PVSA_CPU0
  PL12A_PCLKT3_0  = CLK_25M_CPLD
  PL11B  = TP_CPLD1_PL11A
  PL12D  = PWRGD_PVCCMCP_CPU1
  PL11D  = PWRGD_CPU0_LVC3
  GND(14)  = GND
  PB8D  = FM_OC0_USB_N
  PB11D  = PWRGD_PVCCIO_CPU0
  PB12D  = FM_IE_DISABLE_N
  PB18D  = FM_SOL_UART_CH_SEL
  GND(15)  = GND
  PR10D  = PWRGD_P3V3_STBY
  PR12D  = TP_CPLD1_PR12D
  PR11B  = TP_CPLD1_PR11B
  PR12A  = FM_THERMTRIP_DLY
  PR11A  = PWRGD_PVCCIO_CPU1
  PL12B_PCLKC3_0  = RST_RSMRST_DLY
  PL14A  = PWRGD_PVPP_GHJ
  PL13A  = RST_PCIE_RISER1_PERST_N
  VCCIO3(0)  = P3V3_STBY
  GND(16)  = GND
  PB11C  = PWRGD_PVPP_DEF
  PB9C  = FM_PVCCIO_CPU0_EN
  PB16C  = FM_PVCCMCP_CPU1_EN
  PB18C  = FM_CPLD_UART_CH_LOCK_N
  PB21C  = PWRGD_CPU1_LVC3
  PB19D  = XDP_PWRGD_RST_N
  GND(17)  = GND
  VCCIO1(3)  = P3V3_STBY
  PR13A  = FM_CPU1_PROC_ID1
  PR13B  = FM_CPU1_PROC_ID0
  PR12B  = FM_CPU0_FIVR_FAULT_LVT3
  PL13B  = PWRGD_PVCCIN_CPU1
  PL13C  = PWRGD_PVPP_KLM
  PL14B  = RST_CD_CPU0_POR_N
  GND(18)  = GND
  VCCIO2(3)  = P3V3_STBY
  PB8C  = PWRGD_PVCCIOMCP_CPU0
  PB9D  = PWRGD_PVPP_ABC
  PB12C  = FM_156M_CPU1_BRD_OSC_EN
  PB16D  = FM_CPLD_BMC_PWRDN_N
  PB19C  = RST_CPU1_LVC3_R1_N
  PB21D  = XDP_SYSPWROK
  VCCIO2(1)  = P3V3_STBY
  GND(19)  = GND
  PR14B  = FM_CPU1_VRM_OSC_EN
  PR13C  = FM_CPU0_THERMTRIP_LVT3_N
  PR14A  = FM_PVCCIN_PVCCSA_CPU1_EN_LVC1
  PL13D  = FM_GLOBAL_RST_WARN_N
  PL14D  = FM_UART_ALERT_N
  GND(20)  = GND
  PB3A  = FM_CPU1_RC_EN
  PB5B  = PWRGD_PVCCMCP_CPU0
  PB8A_MCLK_CCLK  = TP_CPLD1_PB8A_MCLK_CCLK
  PB9B  = FM_PVCCIOMCP_CPU1_EN
  PB12A  = PWRGD_PVNN_P1V05_PCH
  PB16B_PCLKC2_1  = TP_CPLD1_PB16B_PCLKC2_1
  PB19A  = RST_CD_CPU1_POR_N
  PB21B  = FM_UARTSW_MSB_N
  PB24A  = FM_CPU1_PKGID1
  PB25B_SI_SISPI  = TP_CPLD1_PB25B_SI_SISPI
  GND(21)  = GND
  PR14C  = FM_PVPP_CPU0_EN
  PR13D  = FM_PVPP_CPU1_EN
  PL14C  = FM_BMC_CPLD_GPO
  GND(22)  = GND
  PB3D  = FM_CPU0_RC_EN
  PB6D  = FM_BMC_CPLD_MP_RST_N
  PB5A_CSSPIN  = TP_CPLD1_PB5A_CSSPIN
  PB6B  = RST_PCIE_M2_DEV_N
  PB9A  = PWRGD_PVTT_CPU1
  PB11B_PCLKC2_0  = FM_CPLD_USB_P0_EN_N
  PB18A  = FM_UARTSW_LSB_N
  PB19B  = RST_CPU0_LVC3_R1_N
  PB22A  = FM_DB1200ZL_BCLKS_EN_N
  PB25A_SN  = FM_CPU1_PKGID0
  PB22C  = FM_CPU0_VRM_OSC_EN
  PB25D  = FM_CPU_CATERR_LVT3_N
  GND(23)  = GND
  PR14D  = FM_P12V_MAIN_SW_EN
  VCC(2)  = P3V3_STBY
  PB3C  = FM_ADR_MODE_SEL
  PB6C  = FM_DIS_ADR_DLY
  PB3B  = PWRGD_PVSA_CPU1
  PB6A  = PWRGD_PVCCIOMCP_CPU1
  PB8B_SO_SPISO  = TP_CPLD1_PB8B_SO_SPISO
  PB11A_PCLKT2_0  = FM_PVCCIO_CPU1_EN
  PB12B  = FM_CPLD_DBG_PWR_EN_N
  PB16A_PCLKT2_1  = TP_CPLD1_PB16A_PCLKT2_1
  PB18B  = FM_156M_CPU0_BRD_OSC_EN
  PB21A  = FM_CPU1_PKGID2
  PB22B  = FM_CPU1_SKTOCC_LVT3_N
  PB24B  = FM_CPU_MSMI_LVT3_N
  PB22D  = FM_CPU0_SKTOCC_LVT3_N
  PB25C  = PWRGD_DRAMPWRGD
  VCC(3)  = P3V3_STBY

(kicad_pcb
	(version 20260206)
	(generator "pcbnew")
	(generator_version "10.0")
	(general
		(thickness 1.6)
		(legacy_teardrops no)
	)
	(paper "A4")
	(title_block
		(title "Wiwynn_Tioga_Pass_MB.brd")
		(comment 1 "Tioga Pass / footprint 2035 of 4770 (U8D7), pads 226-256 of 256")
	)
	(layers
		(0 "F.Cu" signal "TOP")
		(4 "In1.Cu" signal "L2GND")
		(6 "In2.Cu" signal "L3")
		(8 "In3.Cu" signal "L4GND")
		(10 "In4.Cu" signal "L5")
		(12 "In5.Cu" signal "L6GND")
		(14 "In6.Cu" signal "L7VCC")
		(16 "In7.Cu" signal "L8VCC")
		(18 "In8.Cu" signal "L9GND")
		(20 "In9.Cu" signal "L10")
		(22 "In10.Cu" signal "L11GND")
		(24 "In11.Cu" signal "L12")
		(26 "In12.Cu" signal "L13GND")
		(2 "B.Cu" signal "BOTTOM")
		(9 "F.Adhes" user "F.Adhesive")
		(11 "B.Adhes" user "B.Adhesive")
		(13 "F.Paste" user "Package Geometry/Pastemask Top")
		(15 "B.Paste" user "Package Geometry/Pastemask Bottom")
		(5 "F.SilkS" user "Ref Des/Silkscreen Top")
		(7 "B.SilkS" user "Ref Des/Silkscreen Bottom")
		(1 "F.Mask" user "Board Geometry/Soldermask Top")
		(3 "B.Mask" user "Board Geometry/Soldermask Bottom")
		(17 "Dwgs.User" user "User.Drawings")
		(19 "Cmts.User" user "User.Comments")
		(21 "Eco1.User" user "User.Eco1")
		(23 "Eco2.User" user "User.Eco2")
		(25 "Edge.Cuts" user "Board Geometry/Outline")
		(27 "Margin" user)
		(31 "F.CrtYd" user "Package Geometry/Place Bound Top")
		(29 "B.CrtYd" user "Package Geometry/Place Bound Bottom")
		(35 "F.Fab" user "Ref Des/Assembly Top")
		(33 "B.Fab" user "Ref Des/Assembly Bottom")
	)
	(footprint ""
		(layer "F.Cu")
		(at 372.745 -74.295 180)
		(property "Reference" "U8D7"
			(at -0.635 -8.28167 0)
			(unlocked yes)
			(layer "F.SilkS")
			(effects
				(font
					(size 0.7874 0.5842)
					(thickness 0.1524)
				)
			)
		)
		(property "Value" ""
			(at 0 0 180)
			(layer "F.Fab")
			(effects
				(font
					(size 1.27 1.27)
				)
			)
		)
		(duplicate_pad_numbers_are_jumpers no)
		(pad "R2" smd circle
			(at -5.199888 5.199888 180)
			(size 0.3556 0.3556)
			(layers "F.Cu" "F.Mask" "F.Paste")
			(net "GND")
		)
		(pad "R3" smd circle
			(at -4.400042 5.199888 180)
			(size 0.3556 0.3556)
			(layers "F.Cu" "F.Mask" "F.Paste")
			(net "FM_CPU0_RC_EN")
		)
		(pad "R4" smd circle
			(at -3.599942 5.199888 180)
			(size 0.3556 0.3556)
			(layers "F.Cu" "F.Mask" "F.Paste")
			(net "FM_BMC_CPLD_MP_RST_N")
		)
		(pad "R5" smd circle
			(at -2.800096 5.199888 180)
			(size 0.3556 0.3556)
			(layers "F.Cu" "F.Mask" "F.Paste")
			(net "TP_CPLD1_PB5A_CSSPIN")
		)
		(pad "R6" smd circle
			(at -1.999996 5.199888 180)
			(size 0.3556 0.3556)
			(layers "F.Cu" "F.Mask" "F.Paste")
			(net "RST_PCIE_M2_DEV_N")
		)
		(pad "R7" smd circle
			(at -1.199896 5.199888 180)
			(size 0.3556 0.3556)
			(layers "F.Cu" "F.Mask" "F.Paste")
			(net "PWRGD_PVTT_CPU1")
		)
		(pad "R8" smd circle
			(at -0.40005 5.199888 180)
			(size 0.3556 0.3556)
			(layers "F.Cu" "F.Mask" "F.Paste")
			(net "FM_CPLD_USB_P0_EN_N")
		)
		(pad "R9" smd circle
			(at 0.40005 5.199888 180)
			(size 0.3556 0.3556)
			(layers "F.Cu" "F.Mask" "F.Paste")
			(net "FM_UARTSW_LSB_N")
		)
		(pad "R10" smd circle
			(at 1.199896 5.199888 180)
			(size 0.3556 0.3556)
			(layers "F.Cu" "F.Mask" "F.Paste")
			(net "RST_CPU0_LVC3_R1_N")
		)
		(pad "R11" smd circle
			(at 1.999996 5.199888 180)
			(size 0.3556 0.3556)
			(layers "F.Cu" "F.Mask" "F.Paste")
			(net "FM_DB1200ZL_BCLKS_EN_N")
		)
		(pad "R12" smd circle
			(at 2.800096 5.199888 180)
			(size 0.3556 0.3556)
			(layers "F.Cu" "F.Mask" "F.Paste")
			(net "FM_CPU1_PKGID0")
		)
		(pad "R13" smd circle
			(at 3.599942 5.199888 180)
			(size 0.3556 0.3556)
			(layers "F.Cu" "F.Mask" "F.Paste")
			(net "FM_CPU0_VRM_OSC_EN")
		)
		(pad "R14" smd circle
			(at 4.400042 5.199888 180)
			(size 0.3556 0.3556)
			(layers "F.Cu" "F.Mask" "F.Paste")
			(net "FM_CPU_CATERR_LVT3_N")
		)
		(pad "R15" smd circle
			(at 5.199888 5.199888 180)
			(size 0.3556 0.3556)
			(layers "F.Cu" "F.Mask" "F.Paste")
			(net "GND")
		)
		(pad "R16" smd circle
			(at 5.999988 5.199888 180)
			(size 0.3556 0.3556)
			(layers "F.Cu" "F.Mask" "F.Paste")
			(net "FM_P12V_MAIN_SW_EN")
		)
		(pad "T1" smd circle
			(at -5.999988 5.999988 180)
			(size 0.3556 0.3556)
			(layers "F.Cu" "F.Mask" "F.Paste")
			(net "P3V3_STBY")
		)
		(pad "T2" smd circle
			(at -5.199888 5.999988 180)
			(size 0.3556 0.3556)
			(layers "F.Cu" "F.Mask" "F.Paste")
			(net "FM_ADR_MODE_SEL")
		)
		(pad "T3" smd circle
			(at -4.400042 5.999988 180)
			(size 0.3556 0.3556)
			(layers "F.Cu" "F.Mask" "F.Paste")
			(net "FM_DIS_ADR_DLY")
		)
		(pad "T4" smd circle
			(at -3.599942 5.999988 180)
			(size 0.3556 0.3556)
			(layers "F.Cu" "F.Mask" "F.Paste")
			(net "PWRGD_PVSA_CPU1")
		)
		(pad "T5" smd circle
			(at -2.800096 5.999988 180)
			(size 0.3556 0.3556)
			(layers "F.Cu" "F.Mask" "F.Paste")
			(net "PWRGD_PVCCIOMCP_CPU1")
		)
		(pad "T6" smd circle
			(at -1.999996 5.999988 180)
			(size 0.3556 0.3556)
			(layers "F.Cu" "F.Mask" "F.Paste")
			(net "TP_CPLD1_PB8B_SO_SPISO")
		)
		(pad "T7" smd circle
			(at -1.199896 5.999988 180)
			(size 0.3556 0.3556)
			(layers "F.Cu" "F.Mask" "F.Paste")
			(net "FM_PVCCIO_CPU1_EN")
		)
		(pad "T8" smd circle
			(at -0.40005 5.999988 180)
			(size 0.3556 0.3556)
			(layers "F.Cu" "F.Mask" "F.Paste")
			(net "FM_CPLD_DBG_PWR_EN_N")
		)
		(pad "T9" smd circle
			(at 0.40005 5.999988 180)
			(size 0.3556 0.3556)
			(layers "F.Cu" "F.Mask" "F.Paste")
			(net "TP_CPLD1_PB16A_PCLKT2_1")
		)
		(pad "T10" smd circle
			(at 1.199896 5.999988 180)
			(size 0.3556 0.3556)
			(layers "F.Cu" "F.Mask" "F.Paste")
			(net "FM_156M_CPU0_BRD_OSC_EN")
		)
		(pad "T11" smd circle
			(at 1.999996 5.999988 180)
			(size 0.3556 0.3556)
			(layers "F.Cu" "F.Mask" "F.Paste")
			(net "FM_CPU1_PKGID2")
		)
		(pad "T12" smd circle
			(at 2.800096 5.999988 180)
			(size 0.3556 0.3556)
			(layers "F.Cu" "F.Mask" "F.Paste")
			(net "FM_CPU1_SKTOCC_LVT3_N")
		)
		(pad "T13" smd circle
			(at 3.599942 5.999988 180)
			(size 0.3556 0.3556)
			(layers "F.Cu" "F.Mask" "F.Paste")
			(net "FM_CPU_MSMI_LVT3_N")
		)
		(pad "T14" smd circle
			(at 4.400042 5.999988 180)
			(size 0.3556 0.3556)
			(layers "F.Cu" "F.Mask" "F.Paste")
			(net "FM_CPU0_SKTOCC_LVT3_N")
		)
		(pad "T15" smd circle
			(at 5.199888 5.999988 180)
			(size 0.3556 0.3556)
			(layers "F.Cu" "F.Mask" "F.Paste")
			(net "PWRGD_DRAMPWRGD")
		)
		(pad "T16" smd circle
			(at 5.999988 5.999988 180)
			(size 0.3556 0.3556)
			(layers "F.Cu" "F.Mask" "F.Paste")
			(net "P3V3_STBY")
		)
	)
)
